# BASEBOARD_FAB2 (Tioga Pass) — schematic netlist excerpt (pin names and nets, part order shuffled) for the footprints in the layout excerpt that follows; sources: Cadence DE-HDL packaged netlist, KiCad conversion of Wiwynn_Tioga_Pass_MB.brd

R9G20  RES  0.0 5% CHIP  pkg 0402  page 141 : A = NIC_MDI_SPRV_RJ45_1_DN ; B = NIC_MDI_SPRV_RJ45_1_R_DN
R6F11  RES  0.0 5% EMPTY  pkg 0402  page 104 : A = CLK_322M_156M_CPU0_OSC_VRM_DP ; B = CLK_322M_OSC_CPU0_RC_DP

(kicad_pcb
	(version 20260206)
	(generator "pcbnew")
	(generator_version "10.0")
	(general
		(thickness 1.6)
		(legacy_teardrops no)
	)
	(paper "A4")
	(title_block
		(title "Wiwynn_Tioga_Pass_MB.brd")
		(comment 1 "Tioga Pass / footprints 2237-2238 of 4770")
	)
	(layers
		(0 "F.Cu" signal "TOP")
		(4 "In1.Cu" signal "L2GND")
		(6 "In2.Cu" signal "L3")
		(8 "In3.Cu" signal "L4GND")
		(10 "In4.Cu" signal "L5")
		(12 "In5.Cu" signal "L6GND")
		(14 "In6.Cu" signal "L7VCC")
		(16 "In7.Cu" signal "L8VCC")
		(18 "In8.Cu" signal "L9GND")
		(20 "In9.Cu" signal "L10")
		(22 "In10.Cu" signal "L11GND")
		(24 "In11.Cu" signal "L12")
		(26 "In12.Cu" signal "L13GND")
		(2 "B.Cu" signal "BOTTOM")
		(9 "F.Adhes" user "F.Adhesive")
		(11 "B.Adhes" user "B.Adhesive")
		(13 "F.Paste" user "Package Geometry/Pastemask Top")
		(15 "B.Paste" user "Package Geometry/Pastemask Bottom")
		(5 "F.SilkS" user "Ref Des/Silkscreen Top")
		(7 "B.SilkS" user "Ref Des/Silkscreen Bottom")
		(1 "F.Mask" user "Board Geometry/Soldermask Top")
		(3 "B.Mask" user "Board Geometry/Soldermask Bottom")
		(17 "Dwgs.User" user "User.Drawings")
		(19 "Cmts.User" user "User.Comments")
		(21 "Eco1.User" user "User.Eco1")
		(23 "Eco2.User" user "User.Eco2")
		(25 "Edge.Cuts" user "Board Geometry/Outline")
		(27 "Margin" user)
		(31 "F.CrtYd" user "Package Geometry/Place Bound Top")
		(29 "B.CrtYd" user "Package Geometry/Place Bound Bottom")
		(35 "F.Fab" user "Ref Des/Assembly Top")
		(33 "B.Fab" user "Ref Des/Assembly Bottom")
	)
	(footprint ""
		(layer "F.Cu")
		(at 478.545144 -15.251938 -90)
		(property "Reference" "R9G20"
			(at -0.8382 -0.67818 270)
			(unlocked yes)
			(layer "F.SilkS")
			(effects
				(font
					(size 0.4064 0.254)
					(thickness 0.1524)
				)
				(justify left)
			)
		)
		(property "Value" ""
			(at 0 0 270)
			(layer "F.Fab")
			(effects
				(font
					(size 1.27 1.27)
				)
			)
		)
		(duplicate_pad_numbers_are_jumpers no)
		(fp_poly
			(pts
				(xy -0.2794 -0.1016) (xy 0.2794 -0.1016) (xy 0.2794 0.9906) (xy -0.2794 0.9906)
			)
			(stroke
				(width 0)
				(type default)
			)
			(fill no)
			(layer "F.CrtYd")
		)
		(fp_line
			(start -0.2794 0.9906)
			(end 0.2794 0.9906)
			(stroke
				(width 0.1)
				(type default)
			)
			(layer "F.Fab")
		)
		(fp_line
			(start 0.2794 0.9906)
			(end 0.2794 -0.1016)
			(stroke
				(width 0.1)
				(type default)
			)
			(layer "F.Fab")
		)
		(fp_line
			(start -0.2794 -0.1016)
			(end -0.2794 0.9906)
			(stroke
				(width 0.1)
				(type default)
			)
			(layer "F.Fab")
		)
		(fp_line
			(start 0.2794 -0.1016)
			(end -0.2794 -0.1016)
			(stroke
				(width 0.1)
				(type default)
			)
			(layer "F.Fab")
		)
		(pad "1" smd rect
			(at 0 0 270)
			(size 0.508 0.508)
			(layers "F.Cu" "F.Mask" "F.Paste")
			(net "NIC_MDI_SPRV_RJ45_1_DN")
		)
		(pad "2" smd rect
			(at 0 0.889 270)
			(size 0.508 0.508)
			(layers "F.Cu" "F.Mask" "F.Paste")
			(net "NIC_MDI_SPRV_RJ45_1_R_DN")
		)
		(zone
			(layer "F.Cu")
			(hatch none 0.5)
			(connect_pads
				(clearance 0)
			)
			(min_thickness 0.25)
			(keepout
				(tracks not_allowed)
				(vias allowed)
				(pads allowed)
				(copperpour not_allowed)
				(footprints allowed)
			)
			(placement
				(enabled no)
				(sheetname "")
			)
			(fill
				(thermal_gap 0.5)
				(thermal_bridge_width 0.5)
				(island_removal_mode 0)
			)
			(polygon
				(pts
					(xy 477.910144 -15.505938) (xy 477.910144 -14.997938) (xy 478.291144 -14.997938) (xy 478.291144 -15.505938)
				)
			)
		)
		(zone
			(layer "F.Cu")
			(hatch none 0.5)
			(connect_pads
				(clearance 0)
			)
			(min_thickness 0.25)
			(keepout
				(tracks allowed)
				(vias not_allowed)
				(pads allowed)
				(copperpour not_allowed)
				(footprints allowed)
			)
			(placement
				(enabled no)
				(sheetname "")
			)
			(fill
				(thermal_gap 0.5)
				(thermal_bridge_width 0.5)
				(island_removal_mode 0)
			)
			(polygon
				(pts
					(xy 478.291144 -15.505938) (xy 478.291144 -14.997938) (xy 477.910144 -14.997938) (xy 477.910144 -15.505938)
				)
			)
		)
	)
	(footprint ""
		(layer "F.Cu")
		(at 318.8716 -28.045918 -90)
		(property "Reference" "R6F11"
			(at 0 0 270)
			(layer "F.SilkS")
			(hide yes)
			(effects
				(font
					(size 1.27 1.27)
				)
			)
		)
		(property "Value" ""
			(at 0 0 270)
			(layer "F.Fab")
			(effects
				(font
					(size 1.27 1.27)
				)
			)
		)
		(duplicate_pad_numbers_are_jumpers no)
		(fp_poly
			(pts
				(xy -0.2794 -0.1016) (xy 0.2794 -0.1016) (xy 0.2794 0.9906) (xy -0.2794 0.9906)
			)
			(stroke
				(width 0)
				(type default)
			)
			(fill no)
			(layer "F.CrtYd")
		)
		(fp_line
			(start -0.2794 0.9906)
			(end 0.2794 0.9906)
			(stroke
				(width 0.1)
				(type default)
			)
			(layer "F.Fab")
		)
		(fp_line
			(start 0.2794 0.9906)
			(end 0.2794 -0.1016)
			(stroke
				(width 0.1)
				(type default)
			)
			(layer "F.Fab")
		)
		(fp_line
			(start -0.2794 -0.1016)
			(end -0.2794 0.9906)
			(stroke
				(width 0.1)
				(type default)
			)
			(layer "F.Fab")
		)
		(fp_line
			(start 0.2794 -0.1016)
			(end -0.2794 -0.1016)
			(stroke
				(width 0.1)
				(type default)
			)
			(layer "F.Fab")
		)
		(pad "1" smd rect
			(at 0 0 270)
			(size 0.508 0.508)
			(layers "F.Cu" "F.Mask" "F.Paste")
			(net "CLK_322M_156M_CPU0_OSC_VRM_DP")
		)
		(pad "2" smd rect
			(at 0 0.889 270)
			(size 0.508 0.508)
			(layers "F.Cu" "F.Mask" "F.Paste")
			(net "CLK_322M_OSC_CPU0_RC_DP")
		)
		(zone
			(layer "F.Cu")
			(hatch none 0.5)
			(connect_pads
				(clearance 0)
			)
			(min_thickness 0.25)
			(keepout
				(tracks not_allowed)
				(vias allowed)
				(pads allowed)
				(copperpour not_allowed)
				(footprints allowed)
			)
			(placement
				(enabled no)
				(sheetname "")
			)
			(fill
				(thermal_gap 0.5)
				(thermal_bridge_width 0.5)
				(island_removal_mode 0)
			)
			(polygon
				(pts
					(xy 318.2366 -28.299918) (xy 318.2366 -27.791918) (xy 318.6176 -27.791918) (xy 318.6176 -28.299918)
				)
			)
		)
		(zone
			(layer "F.Cu")
			(hatch none 0.5)
			(connect_pads
				(clearance 0)
			)
			(min_thickness 0.25)
			(keepout
				(tracks allowed)
				(vias not_allowed)
				(pads allowed)
				(copperpour not_allowed)
				(footprints allowed)
			)
			(placement
				(enabled no)
				(sheetname "")
			)
			(fill
				(thermal_gap 0.5)
				(thermal_bridge_width 0.5)
				(island_removal_mode 0)
			)
			(polygon
				(pts
					(xy 318.6176 -28.299918) (xy 318.6176 -27.791918) (xy 318.2366 -27.791918) (xy 318.2366 -28.299918)
				)
			)
		)
	)
)
